# T6G (Grand Teton) — schematic netlist excerpt (pin names and nets, part order shuffled) for the footprints in the layout excerpt that follows; sources: Cadence DE-HDL packaged netlist, KiCad conversion of 04192023_DAF0TMB3IC0_F0TG_MB_C_brd_V02_OCP.brd

R6087  Q_RES  10K 1% EMPTY  pkg 0402LF  page 210 : A = PVDDCR_SOC_P1_EN_RC ; B = GND
R650  Q_RES  0 5% CHIP  pkg 0402LF  page 362 : A = PWRGD_P0V9_RETIMER_CPU0 ; B = PWRGD_P0V9_RETIMER_CPU0_R
C6652  Q_CAP_DIFFBUS  DIFF BUS_0.22UF 6.3V 20% X6S  pkg C0201  page 319 : \1\ = P5E_CPU1_P0_TX_BUF_C_DN<11> ; \2\ = P5E_CPU1_P0_TX_BUF_DN<11>

(kicad_pcb
	(version 20260206)
	(generator "pcbnew")
	(generator_version "10.0")
	(general
		(thickness 1.6)
		(legacy_teardrops no)
	)
	(paper "A4")
	(title_block
		(title "04192023_DAF0TMB3IC0_F0TG_MB_C_brd_V02_OCP.brd")
		(comment 1 "Grand Teton / footprints 3834-3836 of 8354")
	)
	(layers
		(0 "F.Cu" signal "TOP")
		(4 "In1.Cu" signal "GND")
		(6 "In2.Cu" signal "IN1")
		(8 "In3.Cu" signal "GND1")
		(10 "In4.Cu" signal "IN2")
		(12 "In5.Cu" signal "GND2")
		(14 "In6.Cu" signal "IN3")
		(16 "In7.Cu" signal "GND3")
		(18 "In8.Cu" signal "VCC")
		(20 "In9.Cu" signal "VCC1")
		(22 "In10.Cu" signal "GND4")
		(24 "In11.Cu" signal "IN4")
		(26 "In12.Cu" signal "GND5")
		(28 "In13.Cu" signal "IN5")
		(30 "In14.Cu" signal "GND6")
		(32 "In15.Cu" signal "IN6")
		(34 "In16.Cu" signal "GND7")
		(2 "B.Cu" signal "BOTTOM")
		(9 "F.Adhes" user "F.Adhesive")
		(11 "B.Adhes" user "B.Adhesive")
		(13 "F.Paste" user "Package Geometry/Pastemask Top")
		(15 "B.Paste" user "Package Geometry/Pastemask Bottom")
		(5 "F.SilkS" user "Ref Des/Silkscreen Top")
		(7 "B.SilkS" user "Ref Des/Silkscreen Bottom")
		(1 "F.Mask" user "Board Geometry/Soldermask Top")
		(3 "B.Mask" user "Board Geometry/Soldermask Bottom")
		(17 "Dwgs.User" user "User.Drawings")
		(19 "Cmts.User" user "User.Comments")
		(21 "Eco1.User" user "User.Eco1")
		(23 "Eco2.User" user "User.Eco2")
		(25 "Edge.Cuts" user "Board Geometry/Outline")
		(27 "Margin" user)
		(31 "F.CrtYd" user "Package Geometry/Place Bound Top")
		(29 "B.CrtYd" user "Package Geometry/Place Bound Bottom")
		(35 "F.Fab" user "Ref Des/Assembly Top")
		(33 "B.Fab" user "Ref Des/Assembly Bottom")
	)
	(footprint ""
		(layer "F.Cu")
		(at 96.715834 -136.052052 -90)
		(property "Reference" "R6087"
			(at 0 0 270)
			(layer "F.SilkS")
			(hide yes)
			(effects
				(font
					(size 1.27 1.27)
				)
			)
		)
		(property "Value" ""
			(at 0 0 270)
			(layer "F.Fab")
			(effects
				(font
					(size 1.27 1.27)
				)
			)
		)
		(duplicate_pad_numbers_are_jumpers no)
		(fp_line
			(start -0.7874 0.4064)
			(end -0.7874 -0.4064)
			(stroke
				(width 0.1524)
				(type default)
			)
			(layer "F.SilkS")
		)
		(fp_line
			(start 0.7874 0.4064)
			(end -0.7874 0.4064)
			(stroke
				(width 0.1524)
				(type default)
			)
			(layer "F.SilkS")
		)
		(fp_line
			(start -0.7874 -0.4064)
			(end 0.7874 -0.4064)
			(stroke
				(width 0.1524)
				(type default)
			)
			(layer "F.SilkS")
		)
		(fp_line
			(start 0.7874 -0.4064)
			(end 0.7874 0.4064)
			(stroke
				(width 0.1524)
				(type default)
			)
			(layer "F.SilkS")
		)
		(fp_line
			(start -0.67945 0.3048)
			(end -0.67945 -0.305054)
			(stroke
				(width 0.1)
				(type default)
			)
			(layer "F.Fab")
		)
		(fp_line
			(start -0.12065 0.3048)
			(end -0.67945 0.3048)
			(stroke
				(width 0.1)
				(type default)
			)
			(layer "F.Fab")
		)
		(fp_line
			(start 0.120396 0.3048)
			(end 0.120396 0.2794)
			(stroke
				(width 0.1)
				(type default)
			)
			(layer "F.Fab")
		)
		(fp_line
			(start 0.67945 0.3048)
			(end 0.120396 0.3048)
			(stroke
				(width 0.1)
				(type default)
			)
			(layer "F.Fab")
		)
		(fp_line
			(start -0.12065 0.2794)
			(end -0.12065 0.3048)
			(stroke
				(width 0.1)
				(type default)
			)
			(layer "F.Fab")
		)
		(fp_line
			(start 0.120396 0.2794)
			(end -0.12065 0.2794)
			(stroke
				(width 0.1)
				(type default)
			)
			(layer "F.Fab")
		)
		(fp_line
			(start -0.12065 -0.2794)
			(end 0.12065 -0.2794)
			(stroke
				(width 0.1)
				(type default)
			)
			(layer "F.Fab")
		)
		(fp_line
			(start 0.12065 -0.2794)
			(end 0.12065 -0.3048)
			(stroke
				(width 0.1)
				(type default)
			)
			(layer "F.Fab")
		)
		(fp_line
			(start 0.12065 -0.3048)
			(end 0.67945 -0.3048)
			(stroke
				(width 0.1)
				(type default)
			)
			(layer "F.Fab")
		)
		(fp_line
			(start 0.67945 -0.3048)
			(end 0.67945 0.3048)
			(stroke
				(width 0.1)
				(type default)
			)
			(layer "F.Fab")
		)
		(fp_line
			(start -0.67945 -0.305054)
			(end -0.12065 -0.305054)
			(stroke
				(width 0.1)
				(type default)
			)
			(layer "F.Fab")
		)
		(fp_line
			(start -0.12065 -0.305054)
			(end -0.12065 -0.2794)
			(stroke
				(width 0.1)
				(type default)
			)
			(layer "F.Fab")
		)
		(pad "1" smd circle
			(at -0.40005 0 270)
			(size 0 0)
			(layers "F.Cu" "F.Mask" "F.Paste")
			(net "PVDDCR_SOC_P1_EN_RC")
		)
		(pad "2" smd circle
			(at 0.40005 0 270)
			(size 0 0)
			(layers "F.Cu" "F.Mask" "F.Paste")
			(net "GND")
		)
	)
	(footprint ""
		(layer "F.Cu")
		(at 439.276744 -428.92091 -90)
		(property "Reference" "R650"
			(at 0 0 270)
			(layer "F.SilkS")
			(hide yes)
			(effects
				(font
					(size 1.27 1.27)
				)
			)
		)
		(property "Value" ""
			(at 0 0 270)
			(layer "F.Fab")
			(effects
				(font
					(size 1.27 1.27)
				)
			)
		)
		(duplicate_pad_numbers_are_jumpers no)
		(fp_line
			(start -0.7874 0.4064)
			(end -0.7874 -0.4064)
			(stroke
				(width 0.1524)
				(type default)
			)
			(layer "F.SilkS")
		)
		(fp_line
			(start 0.7874 0.4064)
			(end -0.7874 0.4064)
			(stroke
				(width 0.1524)
				(type default)
			)
			(layer "F.SilkS")
		)
		(fp_line
			(start -0.7874 -0.4064)
			(end 0.7874 -0.4064)
			(stroke
				(width 0.1524)
				(type default)
			)
			(layer "F.SilkS")
		)
		(fp_line
			(start 0.7874 -0.4064)
			(end 0.7874 0.4064)
			(stroke
				(width 0.1524)
				(type default)
			)
			(layer "F.SilkS")
		)
		(fp_line
			(start -0.67945 0.3048)
			(end -0.67945 -0.305054)
			(stroke
				(width 0.1)
				(type default)
			)
			(layer "F.Fab")
		)
		(fp_line
			(start -0.12065 0.3048)
			(end -0.67945 0.3048)
			(stroke
				(width 0.1)
				(type default)
			)
			(layer "F.Fab")
		)
		(fp_line
			(start 0.120396 0.3048)
			(end 0.120396 0.2794)
			(stroke
				(width 0.1)
				(type default)
			)
			(layer "F.Fab")
		)
		(fp_line
			(start 0.67945 0.3048)
			(end 0.120396 0.3048)
			(stroke
				(width 0.1)
				(type default)
			)
			(layer "F.Fab")
		)
		(fp_line
			(start -0.12065 0.2794)
			(end -0.12065 0.3048)
			(stroke
				(width 0.1)
				(type default)
			)
			(layer "F.Fab")
		)
		(fp_line
			(start 0.120396 0.2794)
			(end -0.12065 0.2794)
			(stroke
				(width 0.1)
				(type default)
			)
			(layer "F.Fab")
		)
		(fp_line
			(start -0.12065 -0.2794)
			(end 0.12065 -0.2794)
			(stroke
				(width 0.1)
				(type default)
			)
			(layer "F.Fab")
		)
		(fp_line
			(start 0.12065 -0.2794)
			(end 0.12065 -0.3048)
			(stroke
				(width 0.1)
				(type default)
			)
			(layer "F.Fab")
		)
		(fp_line
			(start 0.12065 -0.3048)
			(end 0.67945 -0.3048)
			(stroke
				(width 0.1)
				(type default)
			)
			(layer "F.Fab")
		)
		(fp_line
			(start 0.67945 -0.3048)
			(end 0.67945 0.3048)
			(stroke
				(width 0.1)
				(type default)
			)
			(layer "F.Fab")
		)
		(fp_line
			(start -0.67945 -0.305054)
			(end -0.12065 -0.305054)
			(stroke
				(width 0.1)
				(type default)
			)
			(layer "F.Fab")
		)
		(fp_line
			(start -0.12065 -0.305054)
			(end -0.12065 -0.2794)
			(stroke
				(width 0.1)
				(type default)
			)
			(layer "F.Fab")
		)
		(pad "1" smd circle
			(at -0.40005 0 270)
			(size 0 0)
			(layers "F.Cu" "F.Mask" "F.Paste")
			(net "PWRGD_P0V9_RETIMER_CPU0")
		)
		(pad "2" smd circle
			(at 0.40005 0 270)
			(size 0 0)
			(layers "F.Cu" "F.Mask" "F.Paste")
			(net "PWRGD_P0V9_RETIMER_CPU0_R")
		)
	)
	(footprint ""
		(layer "F.Cu")
		(at 81.464404 -408.517344 -90)
		(property "Reference" "C6652"
			(at 0 0 270)
			(layer "F.SilkS")
			(hide yes)
			(effects
				(font
					(size 1.27 1.27)
				)
			)
		)
		(property "Value" ""
			(at 0 0 270)
			(layer "F.Fab")
			(effects
				(font
					(size 1.27 1.27)
				)
			)
		)
		(duplicate_pad_numbers_are_jumpers no)
		(fp_line
			(start -0.299974 0.150114)
			(end -0.299974 -0.150114)
			(stroke
				(width 0.1)
				(type default)
			)
			(layer "F.Fab")
		)
		(fp_line
			(start 0.299974 0.150114)
			(end -0.299974 0.150114)
			(stroke
				(width 0.1)
				(type default)
			)
			(layer "F.Fab")
		)
		(fp_line
			(start -0.299974 -0.150114)
			(end 0.299974 -0.150114)
			(stroke
				(width 0.1)
				(type default)
			)
			(layer "F.Fab")
		)
		(fp_line
			(start 0.299974 -0.150114)
			(end 0.299974 0.150114)
			(stroke
				(width 0.1)
				(type default)
			)
			(layer "F.Fab")
		)
		(pad "1" smd rect
			(at -0.2667 0 270)
			(size 0.3048 0.381)
			(layers "F.Cu" "F.Mask" "F.Paste")
			(net "P5E_CPU1_P0_TX_BUF_C_DN<11>")
		)
		(pad "2" smd rect
			(at 0.2667 0 270)
			(size 0.3048 0.381)
			(layers "F.Cu" "F.Mask" "F.Paste")
			(net "P5E_CPU1_P0_TX_BUF_DN<11>")
		)
	)
)
